# SCM (Grand Teton) — schematic netlist excerpt (pin names and nets, part order shuffled) for the footprints in the layout excerpt that follows; sources: Cadence DE-HDL packaged netlist, KiCad conversion of 12092022_DA0F0TMDCD0_F0T_Management_Board_D_brd_V3_OCP.brd

R697  Q_RES  0 5% CHIP  pkg 0402LF  page 47 : A = LED_POSTCODE_2 ; B = LED_POSTCODE_2_R1
R227  Q_RES  10K 1% CHIP  pkg 0402LF  page 32 : A = P3V3_AUX ; B = JTAG_MB_TMS

(kicad_pcb
	(version 20260206)
	(generator "pcbnew")
	(generator_version "10.0")
	(general
		(thickness 1.6)
		(legacy_teardrops no)
	)
	(paper "A4")
	(title_block
		(title "12092022_DA0F0TMDCD0_F0T_Management_Board_D_brd_V3_OCP.brd")
		(comment 1 "Grand Teton / footprints 1394-1395 of 1440")
	)
	(layers
		(0 "F.Cu" signal "TOP")
		(4 "In1.Cu" signal "GND")
		(6 "In2.Cu" signal "IN1")
		(8 "In3.Cu" signal "GND1")
		(10 "In4.Cu" signal "IN2")
		(12 "In5.Cu" signal "VCC")
		(14 "In6.Cu" signal "VCC1")
		(16 "In7.Cu" signal "IN3")
		(18 "In8.Cu" signal "GND2")
		(20 "In9.Cu" signal "IN4")
		(22 "In10.Cu" signal "GND3")
		(2 "B.Cu" signal "BOTTOM")
		(9 "F.Adhes" user "F.Adhesive")
		(11 "B.Adhes" user "B.Adhesive")
		(13 "F.Paste" user "Package Geometry/Pastemask Top")
		(15 "B.Paste" user "Package Geometry/Pastemask Bottom")
		(5 "F.SilkS" user "Ref Des/Silkscreen Top")
		(7 "B.SilkS" user "Ref Des/Silkscreen Bottom")
		(1 "F.Mask" user "Board Geometry/Soldermask Top")
		(3 "B.Mask" user "Board Geometry/Soldermask Bottom")
		(17 "Dwgs.User" user "User.Drawings")
		(19 "Cmts.User" user "User.Comments")
		(21 "Eco1.User" user "User.Eco1")
		(23 "Eco2.User" user "User.Eco2")
		(25 "Edge.Cuts" user "Board Geometry/Outline")
		(27 "Margin" user)
		(31 "F.CrtYd" user "Package Geometry/Place Bound Top")
		(29 "B.CrtYd" user "Package Geometry/Place Bound Bottom")
		(35 "F.Fab" user "Ref Des/Assembly Top")
		(33 "B.Fab" user "Ref Des/Assembly Bottom")
	)
	(footprint ""
		(layer "B.Cu")
		(at 75.5396 -29.5402 180)
		(property "Reference" "R697"
			(at 0 0 0)
			(layer "B.SilkS")
			(hide yes)
			(effects
				(font
					(size 1.27 1.27)
				)
				(justify mirror)
			)
		)
		(property "Value" ""
			(at 0 0 0)
			(layer "B.Fab")
			(effects
				(font
					(size 1.27 1.27)
				)
				(justify mirror)
			)
		)
		(duplicate_pad_numbers_are_jumpers no)
		(fp_line
			(start 0.7874 0.4064)
			(end 0.7874 -0.4064)
			(stroke
				(width 0.1524)
				(type default)
			)
			(layer "B.SilkS")
		)
		(fp_line
			(start 0.7874 -0.4064)
			(end -0.7874 -0.4064)
			(stroke
				(width 0.1524)
				(type default)
			)
			(layer "B.SilkS")
		)
		(fp_line
			(start -0.7874 0.4064)
			(end 0.7874 0.4064)
			(stroke
				(width 0.1524)
				(type default)
			)
			(layer "B.SilkS")
		)
		(fp_line
			(start -0.7874 -0.4064)
			(end -0.7874 0.4064)
			(stroke
				(width 0.1524)
				(type default)
			)
			(layer "B.SilkS")
		)
		(fp_line
			(start 0.67945 0.3048)
			(end 0.67945 -0.305054)
			(stroke
				(width 0.1)
				(type default)
			)
			(layer "B.Fab")
		)
		(fp_line
			(start 0.67945 -0.305054)
			(end 0.12065 -0.305054)
			(stroke
				(width 0.1)
				(type default)
			)
			(layer "B.Fab")
		)
		(fp_line
			(start 0.12065 0.3048)
			(end 0.67945 0.3048)
			(stroke
				(width 0.1)
				(type default)
			)
			(layer "B.Fab")
		)
		(fp_line
			(start 0.12065 0.2794)
			(end 0.12065 0.3048)
			(stroke
				(width 0.1)
				(type default)
			)
			(layer "B.Fab")
		)
		(fp_line
			(start 0.12065 -0.2794)
			(end -0.12065 -0.2794)
			(stroke
				(width 0.1)
				(type default)
			)
			(layer "B.Fab")
		)
		(fp_line
			(start 0.12065 -0.305054)
			(end 0.12065 -0.2794)
			(stroke
				(width 0.1)
				(type default)
			)
			(layer "B.Fab")
		)
		(fp_line
			(start -0.120396 0.3048)
			(end -0.120396 0.2794)
			(stroke
				(width 0.1)
				(type default)
			)
			(layer "B.Fab")
		)
		(fp_line
			(start -0.120396 0.2794)
			(end 0.12065 0.2794)
			(stroke
				(width 0.1)
				(type default)
			)
			(layer "B.Fab")
		)
		(fp_line
			(start -0.12065 -0.2794)
			(end -0.12065 -0.3048)
			(stroke
				(width 0.1)
				(type default)
			)
			(layer "B.Fab")
		)
		(fp_line
			(start -0.12065 -0.3048)
			(end -0.67945 -0.3048)
			(stroke
				(width 0.1)
				(type default)
			)
			(layer "B.Fab")
		)
		(fp_line
			(start -0.67945 0.3048)
			(end -0.120396 0.3048)
			(stroke
				(width 0.1)
				(type default)
			)
			(layer "B.Fab")
		)
		(fp_line
			(start -0.67945 -0.3048)
			(end -0.67945 0.3048)
			(stroke
				(width 0.1)
				(type default)
			)
			(layer "B.Fab")
		)
		(pad "1" smd circle
			(at 0.40005 0)
			(size 0 0)
			(layers "B.Cu" "B.Mask" "B.Paste")
			(net "LED_POSTCODE_2")
		)
		(pad "2" smd circle
			(at -0.40005 0)
			(size 0 0)
			(layers "B.Cu" "B.Mask" "B.Paste")
			(net "LED_POSTCODE_2_R1")
		)
	)
	(footprint ""
		(layer "B.Cu")
		(at 38.1 -106.3625 -90)
		(property "Reference" "R227"
			(at 0 0 90)
			(layer "B.SilkS")
			(hide yes)
			(effects
				(font
					(size 1.27 1.27)
				)
				(justify mirror)
			)
		)
		(property "Value" ""
			(at 0 0 90)
			(layer "B.Fab")
			(effects
				(font
					(size 1.27 1.27)
				)
				(justify mirror)
			)
		)
		(duplicate_pad_numbers_are_jumpers no)
		(fp_line
			(start -0.7874 0.4064)
			(end 0.7874 0.4064)
			(stroke
				(width 0.1524)
				(type default)
			)
			(layer "B.SilkS")
		)
		(fp_line
			(start 0.7874 0.4064)
			(end 0.7874 -0.4064)
			(stroke
				(width 0.1524)
				(type default)
			)
			(layer "B.SilkS")
		)
		(fp_line
			(start -0.7874 -0.4064)
			(end -0.7874 0.4064)
			(stroke
				(width 0.1524)
				(type default)
			)
			(layer "B.SilkS")
		)
		(fp_line
			(start 0.7874 -0.4064)
			(end -0.7874 -0.4064)
			(stroke
				(width 0.1524)
				(type default)
			)
			(layer "B.SilkS")
		)
		(fp_line
			(start -0.67945 0.3048)
			(end -0.120396 0.3048)
			(stroke
				(width 0.1)
				(type default)
			)
			(layer "B.Fab")
		)
		(fp_line
			(start -0.120396 0.3048)
			(end -0.120396 0.2794)
			(stroke
				(width 0.1)
				(type default)
			)
			(layer "B.Fab")
		)
		(fp_line
			(start 0.12065 0.3048)
			(end 0.67945 0.3048)
			(stroke
				(width 0.1)
				(type default)
			)
			(layer "B.Fab")
		)
		(fp_line
			(start 0.67945 0.3048)
			(end 0.67945 -0.305054)
			(stroke
				(width 0.1)
				(type default)
			)
			(layer "B.Fab")
		)
		(fp_line
			(start -0.120396 0.2794)
			(end 0.12065 0.2794)
			(stroke
				(width 0.1)
				(type default)
			)
			(layer "B.Fab")
		)
		(fp_line
			(start 0.12065 0.2794)
			(end 0.12065 0.3048)
			(stroke
				(width 0.1)
				(type default)
			)
			(layer "B.Fab")
		)
		(fp_line
			(start -0.12065 -0.2794)
			(end -0.12065 -0.3048)
			(stroke
				(width 0.1)
				(type default)
			)
			(layer "B.Fab")
		)
		(fp_line
			(start 0.12065 -0.2794)
			(end -0.12065 -0.2794)
			(stroke
				(width 0.1)
				(type default)
			)
			(layer "B.Fab")
		)
		(fp_line
			(start -0.67945 -0.3048)
			(end -0.67945 0.3048)
			(stroke
				(width 0.1)
				(type default)
			)
			(layer "B.Fab")
		)
		(fp_line
			(start -0.12065 -0.3048)
			(end -0.67945 -0.3048)
			(stroke
				(width 0.1)
				(type default)
			)
			(layer "B.Fab")
		)
		(fp_line
			(start 0.12065 -0.305054)
			(end 0.12065 -0.2794)
			(stroke
				(width 0.1)
				(type default)
			)
			(layer "B.Fab")
		)
		(fp_line
			(start 0.67945 -0.305054)
			(end 0.12065 -0.305054)
			(stroke
				(width 0.1)
				(type default)
			)
			(layer "B.Fab")
		)
		(pad "1" smd circle
			(at 0.40005 0 90)
			(size 0 0)
			(layers "B.Cu" "B.Mask" "B.Paste")
			(net "P3V3_AUX")
		)
		(pad "2" smd circle
			(at -0.40005 0 90)
			(size 0 0)
			(layers "B.Cu" "B.Mask" "B.Paste")
			(net "JTAG_MB_TMS")
		)
	)
)
